# T6G (Grand Teton) — schematic netlist excerpt (pin names and nets, part order shuffled) for the footprints in the layout excerpt that follows; sources: Cadence DE-HDL packaged netlist, KiCad conversion of 04192023_DAF0TMB3IC0_F0TG_MB_C_brd_V02_OCP.brd

R2893  Q_RES  0 5% EMPTY  pkg 0402LF  page 248 : A = SMB_1_BMC_GPU_R_SCL ; B = SMB_1_BMC_GPU_BUF_R_SCL
R1415  Q_RES  1K 1% CHIP  pkg 0201LF  page 185 : A = P1V8_CPU0_RT_1D ; B = SMB_RT_CPU0_P1_ROM_MUX_1D_SDA
PC6621  Q_CAP  100NF 50V 10% X7R  pkg C0402  page 365 : A = SW_P0V9_RETIMER_CPU1_BOOT1_RC ; B = SW_P0V9_RETIMER_CPU1_PH1

(kicad_pcb
	(version 20260206)
	(generator "pcbnew")
	(generator_version "10.0")
	(general
		(thickness 1.6)
		(legacy_teardrops no)
	)
	(paper "A4")
	(title_block
		(title "04192023_DAF0TMB3IC0_F0TG_MB_C_brd_V02_OCP.brd")
		(comment 1 "Grand Teton / footprints 4001-4003 of 8354")
	)
	(layers
		(0 "F.Cu" signal "TOP")
		(4 "In1.Cu" signal "GND")
		(6 "In2.Cu" signal "IN1")
		(8 "In3.Cu" signal "GND1")
		(10 "In4.Cu" signal "IN2")
		(12 "In5.Cu" signal "GND2")
		(14 "In6.Cu" signal "IN3")
		(16 "In7.Cu" signal "GND3")
		(18 "In8.Cu" signal "VCC")
		(20 "In9.Cu" signal "VCC1")
		(22 "In10.Cu" signal "GND4")
		(24 "In11.Cu" signal "IN4")
		(26 "In12.Cu" signal "GND5")
		(28 "In13.Cu" signal "IN5")
		(30 "In14.Cu" signal "GND6")
		(32 "In15.Cu" signal "IN6")
		(34 "In16.Cu" signal "GND7")
		(2 "B.Cu" signal "BOTTOM")
		(9 "F.Adhes" user "F.Adhesive")
		(11 "B.Adhes" user "B.Adhesive")
		(13 "F.Paste" user "Package Geometry/Pastemask Top")
		(15 "B.Paste" user "Package Geometry/Pastemask Bottom")
		(5 "F.SilkS" user "Ref Des/Silkscreen Top")
		(7 "B.SilkS" user "Ref Des/Silkscreen Bottom")
		(1 "F.Mask" user "Board Geometry/Soldermask Top")
		(3 "B.Mask" user "Board Geometry/Soldermask Bottom")
		(17 "Dwgs.User" user "User.Drawings")
		(19 "Cmts.User" user "User.Comments")
		(21 "Eco1.User" user "User.Eco1")
		(23 "Eco2.User" user "User.Eco2")
		(25 "Edge.Cuts" user "Board Geometry/Outline")
		(27 "Margin" user)
		(31 "F.CrtYd" user "Package Geometry/Place Bound Top")
		(29 "B.CrtYd" user "Package Geometry/Place Bound Bottom")
		(35 "F.Fab" user "Ref Des/Assembly Top")
		(33 "B.Fab" user "Ref Des/Assembly Bottom")
	)
	(footprint ""
		(layer "F.Cu")
		(at 18.483072 -393.394184 -90)
		(property "Reference" "PC6621"
			(at 0 0 270)
			(layer "F.SilkS")
			(hide yes)
			(effects
				(font
					(size 1.27 1.27)
				)
			)
		)
		(property "Value" ""
			(at 0 0 270)
			(layer "F.Fab")
			(effects
				(font
					(size 1.27 1.27)
				)
			)
		)
		(duplicate_pad_numbers_are_jumpers no)
		(fp_line
			(start -0.7874 0.4064)
			(end -0.7874 -0.4064)
			(stroke
				(width 0.1524)
				(type default)
			)
			(layer "F.SilkS")
		)
		(fp_line
			(start 0.7874 0.4064)
			(end -0.7874 0.4064)
			(stroke
				(width 0.1524)
				(type default)
			)
			(layer "F.SilkS")
		)
		(fp_line
			(start -0.7874 -0.4064)
			(end 0.7874 -0.4064)
			(stroke
				(width 0.1524)
				(type default)
			)
			(layer "F.SilkS")
		)
		(fp_line
			(start 0.7874 -0.4064)
			(end 0.7874 0.4064)
			(stroke
				(width 0.1524)
				(type default)
			)
			(layer "F.SilkS")
		)
		(fp_line
			(start -0.67945 0.3048)
			(end -0.67945 -0.305054)
			(stroke
				(width 0.1)
				(type default)
			)
			(layer "F.Fab")
		)
		(fp_line
			(start -0.12065 0.3048)
			(end -0.67945 0.3048)
			(stroke
				(width 0.1)
				(type default)
			)
			(layer "F.Fab")
		)
		(fp_line
			(start 0.120396 0.3048)
			(end 0.120396 0.2794)
			(stroke
				(width 0.1)
				(type default)
			)
			(layer "F.Fab")
		)
		(fp_line
			(start 0.67945 0.3048)
			(end 0.120396 0.3048)
			(stroke
				(width 0.1)
				(type default)
			)
			(layer "F.Fab")
		)
		(fp_line
			(start -0.12065 0.2794)
			(end -0.12065 0.3048)
			(stroke
				(width 0.1)
				(type default)
			)
			(layer "F.Fab")
		)
		(fp_line
			(start 0.120396 0.2794)
			(end -0.12065 0.2794)
			(stroke
				(width 0.1)
				(type default)
			)
			(layer "F.Fab")
		)
		(fp_line
			(start -0.12065 -0.2794)
			(end 0.12065 -0.2794)
			(stroke
				(width 0.1)
				(type default)
			)
			(layer "F.Fab")
		)
		(fp_line
			(start 0.12065 -0.2794)
			(end 0.12065 -0.3048)
			(stroke
				(width 0.1)
				(type default)
			)
			(layer "F.Fab")
		)
		(fp_line
			(start 0.12065 -0.3048)
			(end 0.67945 -0.3048)
			(stroke
				(width 0.1)
				(type default)
			)
			(layer "F.Fab")
		)
		(fp_line
			(start 0.67945 -0.3048)
			(end 0.67945 0.3048)
			(stroke
				(width 0.1)
				(type default)
			)
			(layer "F.Fab")
		)
		(fp_line
			(start -0.67945 -0.305054)
			(end -0.12065 -0.305054)
			(stroke
				(width 0.1)
				(type default)
			)
			(layer "F.Fab")
		)
		(fp_line
			(start -0.12065 -0.305054)
			(end -0.12065 -0.2794)
			(stroke
				(width 0.1)
				(type default)
			)
			(layer "F.Fab")
		)
		(pad "1" smd circle
			(at -0.40005 0 270)
			(size 0 0)
			(layers "F.Cu" "F.Mask" "F.Paste")
			(net "SW_P0V9_RETIMER_CPU1_BOOT1_RC")
		)
		(pad "2" smd circle
			(at 0.40005 0 270)
			(size 0 0)
			(layers "F.Cu" "F.Mask" "F.Paste")
			(net "SW_P0V9_RETIMER_CPU1_PH1")
		)
	)
	(footprint ""
		(layer "F.Cu")
		(at 294.581072 -394.721842 180)
		(property "Reference" "R1415"
			(at 0 0 180)
			(layer "F.SilkS")
			(hide yes)
			(effects
				(font
					(size 1.27 1.27)
				)
			)
		)
		(property "Value" ""
			(at 0 0 180)
			(layer "F.Fab")
			(effects
				(font
					(size 1.27 1.27)
				)
			)
		)
		(duplicate_pad_numbers_are_jumpers no)
		(fp_line
			(start 0.32512 0.175006)
			(end -0.32512 0.175006)
			(stroke
				(width 0.1)
				(type default)
			)
			(layer "F.Fab")
		)
		(fp_line
			(start 0.32512 -0.175006)
			(end 0.32512 0.175006)
			(stroke
				(width 0.1)
				(type default)
			)
			(layer "F.Fab")
		)
		(fp_line
			(start -0.32512 0.175006)
			(end -0.32512 -0.175006)
			(stroke
				(width 0.1)
				(type default)
			)
			(layer "F.Fab")
		)
		(fp_line
			(start -0.32512 -0.175006)
			(end 0.32512 -0.175006)
			(stroke
				(width 0.1)
				(type default)
			)
			(layer "F.Fab")
		)
		(pad "1" smd rect
			(at -0.2667 0 180)
			(size 0.3048 0.381)
			(layers "F.Cu" "F.Mask" "F.Paste")
			(net "P1V8_CPU0_RT_1D")
		)
		(pad "2" smd rect
			(at 0.2667 0)
			(size 0.3048 0.381)
			(layers "F.Cu" "F.Mask" "F.Paste")
			(net "SMB_RT_CPU0_P1_ROM_MUX_1D_SDA")
		)
	)
	(footprint ""
		(layer "F.Cu")
		(at 23.495 -431.9143 90)
		(property "Reference" "R2893"
			(at 0 0 90)
			(layer "F.SilkS")
			(hide yes)
			(effects
				(font
					(size 1.27 1.27)
				)
			)
		)
		(property "Value" ""
			(at 0 0 90)
			(layer "F.Fab")
			(effects
				(font
					(size 1.27 1.27)
				)
			)
		)
		(duplicate_pad_numbers_are_jumpers no)
		(fp_line
			(start 0.7874 -0.4064)
			(end 0.7874 0.4064)
			(stroke
				(width 0.1524)
				(type default)
			)
			(layer "F.SilkS")
		)
		(fp_line
			(start -0.7874 -0.4064)
			(end 0.7874 -0.4064)
			(stroke
				(width 0.1524)
				(type default)
			)
			(layer "F.SilkS")
		)
		(fp_line
			(start 0.7874 0.4064)
			(end -0.7874 0.4064)
			(stroke
				(width 0.1524)
				(type default)
			)
			(layer "F.SilkS")
		)
		(fp_line
			(start -0.7874 0.4064)
			(end -0.7874 -0.4064)
			(stroke
				(width 0.1524)
				(type default)
			)
			(layer "F.SilkS")
		)
		(fp_line
			(start -0.12065 -0.305054)
			(end -0.12065 -0.2794)
			(stroke
				(width 0.1)
				(type default)
			)
			(layer "F.Fab")
		)
		(fp_line
			(start -0.67945 -0.305054)
			(end -0.12065 -0.305054)
			(stroke
				(width 0.1)
				(type default)
			)
			(layer "F.Fab")
		)
		(fp_line
			(start 0.67945 -0.3048)
			(end 0.67945 0.3048)
			(stroke
				(width 0.1)
				(type default)
			)
			(layer "F.Fab")
		)
		(fp_line
			(start 0.12065 -0.3048)
			(end 0.67945 -0.3048)
			(stroke
				(width 0.1)
				(type default)
			)
			(layer "F.Fab")
		)
		(fp_line
			(start 0.12065 -0.2794)
			(end 0.12065 -0.3048)
			(stroke
				(width 0.1)
				(type default)
			)
			(layer "F.Fab")
		)
		(fp_line
			(start -0.12065 -0.2794)
			(end 0.12065 -0.2794)
			(stroke
				(width 0.1)
				(type default)
			)
			(layer "F.Fab")
		)
		(fp_line
			(start 0.120396 0.2794)
			(end -0.12065 0.2794)
			(stroke
				(width 0.1)
				(type default)
			)
			(layer "F.Fab")
		)
		(fp_line
			(start -0.12065 0.2794)
			(end -0.12065 0.3048)
			(stroke
				(width 0.1)
				(type default)
			)
			(layer "F.Fab")
		)
		(fp_line
			(start 0.67945 0.3048)
			(end 0.120396 0.3048)
			(stroke
				(width 0.1)
				(type default)
			)
			(layer "F.Fab")
		)
		(fp_line
			(start 0.120396 0.3048)
			(end 0.120396 0.2794)
			(stroke
				(width 0.1)
				(type default)
			)
			(layer "F.Fab")
		)
		(fp_line
			(start -0.12065 0.3048)
			(end -0.67945 0.3048)
			(stroke
				(width 0.1)
				(type default)
			)
			(layer "F.Fab")
		)
		(fp_line
			(start -0.67945 0.3048)
			(end -0.67945 -0.305054)
			(stroke
				(width 0.1)
				(type default)
			)
			(layer "F.Fab")
		)
		(pad "1" smd circle
			(at -0.40005 0 90)
			(size 0 0)
			(layers "F.Cu" "F.Mask" "F.Paste")
			(net "SMB_1_BMC_GPU_R_SCL")
		)
		(pad "2" smd circle
			(at 0.40005 0 90)
			(size 0 0)
			(layers "F.Cu" "F.Mask" "F.Paste")
			(net "SMB_1_BMC_GPU_BUF_R_SCL")
		)
	)
)
